# S9S_MB_2U (Grand Teton) — schematic netlist excerpt (pin names and nets, part order shuffled) for the footprints in the layout excerpt that follows; sources: Cadence DE-HDL packaged netlist, KiCad conversion of 03242023_DA0F0TMBIJ0_F0T_Motherboard_J_brd_V01_OCP.brd

R748  Q_RES  75 1% CHIP  pkg 0402LF  page 132 : A = P1V05_PCH_AUX ; B = JTAG_DBP_TDI_PCH
R4753  Q_RES  0 5% CHIP  pkg 0402LF  page 162 : A = HP_LVC3_OCP_V3_2_PRSNT2_N_R ; B = HP_LVC3_OCP_V3_2_PRSNT2_PLD_N
C892  Q_CAP_DIFFBUS  DIFF BUS_0.22UF 6.3V 20% X6S  pkg C0201  page 174 : \1\ = P5E_CPU0_PE3_TX_C_DN<4> ; \2\ = P5E_CPU0_PE3_TX_DN<4>

(kicad_pcb
	(version 20260206)
	(generator "pcbnew")
	(generator_version "10.0")
	(general
		(thickness 1.6)
		(legacy_teardrops no)
	)
	(paper "A4")
	(title_block
		(title "03242023_DA0F0TMBIJ0_F0T_Motherboard_J_brd_V01_OCP.brd")
		(comment 1 "Grand Teton / footprints 1888-1890 of 6105")
	)
	(layers
		(0 "F.Cu" signal "TOP")
		(4 "In1.Cu" signal "GND")
		(6 "In2.Cu" signal "IN1")
		(8 "In3.Cu" signal "GND1")
		(10 "In4.Cu" signal "IN2")
		(12 "In5.Cu" signal "GND2")
		(14 "In6.Cu" signal "IN3")
		(16 "In7.Cu" signal "GND3")
		(18 "In8.Cu" signal "VCC")
		(20 "In9.Cu" signal "VCC1")
		(22 "In10.Cu" signal "GND4")
		(24 "In11.Cu" signal "IN4")
		(26 "In12.Cu" signal "GND5")
		(28 "In13.Cu" signal "IN5")
		(30 "In14.Cu" signal "GND6")
		(32 "In15.Cu" signal "IN6")
		(34 "In16.Cu" signal "GND7")
		(2 "B.Cu" signal "BOTTOM")
		(9 "F.Adhes" user "F.Adhesive")
		(11 "B.Adhes" user "B.Adhesive")
		(13 "F.Paste" user "Package Geometry/Pastemask Top")
		(15 "B.Paste" user "Package Geometry/Pastemask Bottom")
		(5 "F.SilkS" user "Ref Des/Silkscreen Top")
		(7 "B.SilkS" user "Ref Des/Silkscreen Bottom")
		(1 "F.Mask" user "Board Geometry/Soldermask Top")
		(3 "B.Mask" user "Board Geometry/Soldermask Bottom")
		(17 "Dwgs.User" user "User.Drawings")
		(19 "Cmts.User" user "User.Comments")
		(21 "Eco1.User" user "User.Eco1")
		(23 "Eco2.User" user "User.Eco2")
		(25 "Edge.Cuts" user "Board Geometry/Outline")
		(27 "Margin" user)
		(31 "F.CrtYd" user "Package Geometry/Place Bound Top")
		(29 "B.CrtYd" user "Package Geometry/Place Bound Bottom")
		(35 "F.Fab" user "Ref Des/Assembly Top")
		(33 "B.Fab" user "Ref Des/Assembly Bottom")
	)
	(footprint ""
		(layer "F.Cu")
		(at 358.237282 -57.898792)
		(property "Reference" "R748"
			(at 0 0 0)
			(layer "F.SilkS")
			(hide yes)
			(effects
				(font
					(size 1.27 1.27)
				)
			)
		)
		(property "Value" ""
			(at 0 0 0)
			(layer "F.Fab")
			(effects
				(font
					(size 1.27 1.27)
				)
			)
		)
		(duplicate_pad_numbers_are_jumpers no)
		(fp_line
			(start -0.7874 -0.4064)
			(end 0.7874 -0.4064)
			(stroke
				(width 0.1524)
				(type default)
			)
			(layer "F.SilkS")
		)
		(fp_line
			(start -0.7874 0.4064)
			(end -0.7874 -0.4064)
			(stroke
				(width 0.1524)
				(type default)
			)
			(layer "F.SilkS")
		)
		(fp_line
			(start 0.7874 -0.4064)
			(end 0.7874 0.4064)
			(stroke
				(width 0.1524)
				(type default)
			)
			(layer "F.SilkS")
		)
		(fp_line
			(start 0.7874 0.4064)
			(end -0.7874 0.4064)
			(stroke
				(width 0.1524)
				(type default)
			)
			(layer "F.SilkS")
		)
		(fp_line
			(start -0.67945 -0.305054)
			(end -0.12065 -0.305054)
			(stroke
				(width 0.1)
				(type default)
			)
			(layer "F.Fab")
		)
		(fp_line
			(start -0.67945 0.3048)
			(end -0.67945 -0.305054)
			(stroke
				(width 0.1)
				(type default)
			)
			(layer "F.Fab")
		)
		(fp_line
			(start -0.12065 -0.305054)
			(end -0.12065 -0.2794)
			(stroke
				(width 0.1)
				(type default)
			)
			(layer "F.Fab")
		)
		(fp_line
			(start -0.12065 -0.2794)
			(end 0.12065 -0.2794)
			(stroke
				(width 0.1)
				(type default)
			)
			(layer "F.Fab")
		)
		(fp_line
			(start -0.12065 0.2794)
			(end -0.12065 0.3048)
			(stroke
				(width 0.1)
				(type default)
			)
			(layer "F.Fab")
		)
		(fp_line
			(start -0.12065 0.3048)
			(end -0.67945 0.3048)
			(stroke
				(width 0.1)
				(type default)
			)
			(layer "F.Fab")
		)
		(fp_line
			(start 0.120396 0.2794)
			(end -0.12065 0.2794)
			(stroke
				(width 0.1)
				(type default)
			)
			(layer "F.Fab")
		)
		(fp_line
			(start 0.120396 0.3048)
			(end 0.120396 0.2794)
			(stroke
				(width 0.1)
				(type default)
			)
			(layer "F.Fab")
		)
		(fp_line
			(start 0.12065 -0.3048)
			(end 0.67945 -0.3048)
			(stroke
				(width 0.1)
				(type default)
			)
			(layer "F.Fab")
		)
		(fp_line
			(start 0.12065 -0.2794)
			(end 0.12065 -0.3048)
			(stroke
				(width 0.1)
				(type default)
			)
			(layer "F.Fab")
		)
		(fp_line
			(start 0.67945 -0.3048)
			(end 0.67945 0.3048)
			(stroke
				(width 0.1)
				(type default)
			)
			(layer "F.Fab")
		)
		(fp_line
			(start 0.67945 0.3048)
			(end 0.120396 0.3048)
			(stroke
				(width 0.1)
				(type default)
			)
			(layer "F.Fab")
		)
		(pad "1" smd circle
			(at -0.40005 0)
			(size 0 0)
			(layers "F.Cu" "F.Mask" "F.Paste")
			(net "P1V05_PCH_AUX")
		)
		(pad "2" smd circle
			(at 0.40005 0)
			(size 0 0)
			(layers "F.Cu" "F.Mask" "F.Paste")
			(net "JTAG_DBP_TDI_PCH")
		)
	)
	(footprint ""
		(layer "F.Cu")
		(at 406.43937 -408.517344 -90)
		(property "Reference" "C892"
			(at 0 0 270)
			(layer "F.SilkS")
			(hide yes)
			(effects
				(font
					(size 1.27 1.27)
				)
			)
		)
		(property "Value" ""
			(at 0 0 270)
			(layer "F.Fab")
			(effects
				(font
					(size 1.27 1.27)
				)
			)
		)
		(duplicate_pad_numbers_are_jumpers no)
		(fp_line
			(start -0.299974 0.150114)
			(end -0.299974 -0.150114)
			(stroke
				(width 0.1)
				(type default)
			)
			(layer "F.Fab")
		)
		(fp_line
			(start 0.299974 0.150114)
			(end -0.299974 0.150114)
			(stroke
				(width 0.1)
				(type default)
			)
			(layer "F.Fab")
		)
		(fp_line
			(start -0.299974 -0.150114)
			(end 0.299974 -0.150114)
			(stroke
				(width 0.1)
				(type default)
			)
			(layer "F.Fab")
		)
		(fp_line
			(start 0.299974 -0.150114)
			(end 0.299974 0.150114)
			(stroke
				(width 0.1)
				(type default)
			)
			(layer "F.Fab")
		)
		(pad "1" smd rect
			(at -0.2667 0 270)
			(size 0.3048 0.381)
			(layers "F.Cu" "F.Mask" "F.Paste")
			(net "P5E_CPU0_PE3_TX_C_DN<4>")
		)
		(pad "2" smd rect
			(at 0.2667 0 270)
			(size 0.3048 0.381)
			(layers "F.Cu" "F.Mask" "F.Paste")
			(net "P5E_CPU0_PE3_TX_DN<4>")
		)
	)
	(footprint ""
		(layer "F.Cu")
		(at 28.578048 -69.7992)
		(property "Reference" "R4753"
			(at 0 0 0)
			(layer "F.SilkS")
			(hide yes)
			(effects
				(font
					(size 1.27 1.27)
				)
			)
		)
		(property "Value" ""
			(at 0 0 0)
			(layer "F.Fab")
			(effects
				(font
					(size 1.27 1.27)
				)
			)
		)
		(duplicate_pad_numbers_are_jumpers no)
		(fp_line
			(start -0.7874 -0.4064)
			(end 0.7874 -0.4064)
			(stroke
				(width 0.1524)
				(type default)
			)
			(layer "F.SilkS")
		)
		(fp_line
			(start -0.7874 0.4064)
			(end -0.7874 -0.4064)
			(stroke
				(width 0.1524)
				(type default)
			)
			(layer "F.SilkS")
		)
		(fp_line
			(start 0.7874 -0.4064)
			(end 0.7874 0.4064)
			(stroke
				(width 0.1524)
				(type default)
			)
			(layer "F.SilkS")
		)
		(fp_line
			(start 0.7874 0.4064)
			(end -0.7874 0.4064)
			(stroke
				(width 0.1524)
				(type default)
			)
			(layer "F.SilkS")
		)
		(fp_line
			(start -0.67945 -0.305054)
			(end -0.12065 -0.305054)
			(stroke
				(width 0.1)
				(type default)
			)
			(layer "F.Fab")
		)
		(fp_line
			(start -0.67945 0.3048)
			(end -0.67945 -0.305054)
			(stroke
				(width 0.1)
				(type default)
			)
			(layer "F.Fab")
		)
		(fp_line
			(start -0.12065 -0.305054)
			(end -0.12065 -0.2794)
			(stroke
				(width 0.1)
				(type default)
			)
			(layer "F.Fab")
		)
		(fp_line
			(start -0.12065 -0.2794)
			(end 0.12065 -0.2794)
			(stroke
				(width 0.1)
				(type default)
			)
			(layer "F.Fab")
		)
		(fp_line
			(start -0.12065 0.2794)
			(end -0.12065 0.3048)
			(stroke
				(width 0.1)
				(type default)
			)
			(layer "F.Fab")
		)
		(fp_line
			(start -0.12065 0.3048)
			(end -0.67945 0.3048)
			(stroke
				(width 0.1)
				(type default)
			)
			(layer "F.Fab")
		)
		(fp_line
			(start 0.120396 0.2794)
			(end -0.12065 0.2794)
			(stroke
				(width 0.1)
				(type default)
			)
			(layer "F.Fab")
		)
		(fp_line
			(start 0.120396 0.3048)
			(end 0.120396 0.2794)
			(stroke
				(width 0.1)
				(type default)
			)
			(layer "F.Fab")
		)
		(fp_line
			(start 0.12065 -0.3048)
			(end 0.67945 -0.3048)
			(stroke
				(width 0.1)
				(type default)
			)
			(layer "F.Fab")
		)
		(fp_line
			(start 0.12065 -0.2794)
			(end 0.12065 -0.3048)
			(stroke
				(width 0.1)
				(type default)
			)
			(layer "F.Fab")
		)
		(fp_line
			(start 0.67945 -0.3048)
			(end 0.67945 0.3048)
			(stroke
				(width 0.1)
				(type default)
			)
			(layer "F.Fab")
		)
		(fp_line
			(start 0.67945 0.3048)
			(end 0.120396 0.3048)
			(stroke
				(width 0.1)
				(type default)
			)
			(layer "F.Fab")
		)
		(pad "1" smd circle
			(at -0.40005 0)
			(size 0 0)
			(layers "F.Cu" "F.Mask" "F.Paste")
			(net "HP_LVC3_OCP_V3_2_PRSNT2_N_R")
		)
		(pad "2" smd circle
			(at 0.40005 0)
			(size 0 0)
			(layers "F.Cu" "F.Mask" "F.Paste")
			(net "HP_LVC3_OCP_V3_2_PRSNT2_PLD_N")
		)
	)
)
